(kicad_pcb
	(version 20260206)
	(generator "pcbnew")
	(generator_version "10.0")
	(general
		(thickness 1.6)
		(legacy_teardrops no)
	)
	(paper "A4")
	(title_block
		(title "dpb — 14545-sa.0730WZS0815.brd")
		(comment 1 "Honey Badger (Wiwynn) / footprints 964-970 of 1066")
	)
	(layers
		(0 "F.Cu" signal "TOP")
		(4 "In1.Cu" signal "L2GND")
		(6 "In2.Cu" signal "L3")
		(8 "In3.Cu" signal "L4VCC")
		(10 "In4.Cu" signal "L5VCC")
		(12 "In5.Cu" signal "L6")
		(14 "In6.Cu" signal "L7GND")
		(2 "B.Cu" signal "BOTTOM")
		(9 "F.Adhes" user "F.Adhesive")
		(11 "B.Adhes" user "B.Adhesive")
		(13 "F.Paste" user "Package Geometry/Pastemask Top")
		(15 "B.Paste" user "Package Geometry/Pastemask Bottom")
		(5 "F.SilkS" user "Ref Des/Silkscreen Top")
		(7 "B.SilkS" user "Ref Des/Silkscreen Bottom")
		(1 "F.Mask" user "Board Geometry/Soldermask Top")
		(3 "B.Mask" user "Board Geometry/Soldermask Bottom")
		(17 "Dwgs.User" user "User.Drawings")
		(19 "Cmts.User" user "User.Comments")
		(21 "Eco1.User" user "User.Eco1")
		(23 "Eco2.User" user "User.Eco2")
		(25 "Edge.Cuts" user "Board Geometry/Outline")
		(27 "Margin" user)
		(31 "F.CrtYd" user "Package Geometry/Place Bound Top")
		(29 "B.CrtYd" user "Package Geometry/Place Bound Bottom")
		(35 "F.Fab" user "Ref Des/Assembly Top")
		(33 "B.Fab" user "Ref Des/Assembly Bottom")
	)
	(footprint ""
		(layer "F.Cu")
		(at 66.801746 -386.2197 -90)
		(property "Reference" "Q13"
			(at 0 0 270)
			(layer "F.SilkS")
			(hide yes)
			(effects
				(font
					(size 1.27 1.27)
				)
			)
		)
		(property "Value" "AO4406AL-GP"
			(at -3.707384 -1.5367 270)
			(unlocked yes)
			(layer "F.Fab")
			(hide yes)
			(effects
				(font
					(size 1.016 1.016)
					(thickness 0.1524)
				)
			)
		)
		(property "Device Type" "SOIC8H69"
			(at -3.707384 -3.0607 270)
			(unlocked yes)
			(layer "F.Fab")
			(hide yes)
			(effects
				(font
					(size 1.016 1.016)
					(thickness 0.1524)
				)
			)
		)
		(duplicate_pad_numbers_are_jumpers no)
		(fp_line
			(start -2.6289 3.4417)
			(end -2.6289 1.4732)
			(stroke
				(width 0.381)
				(type default)
			)
			(layer "F.SilkS")
		)
		(fp_line
			(start -2.7432 1.4224)
			(end -2.6416 1.4224)
			(stroke
				(width 0.1524)
				(type default)
			)
			(layer "F.SilkS")
		)
		(fp_line
			(start -2.7432 1.4224)
			(end 2.1336 1.4224)
			(stroke
				(width 0.1524)
				(type default)
			)
			(layer "F.SilkS")
		)
		(fp_line
			(start 2.1336 1.4224)
			(end 2.1336 -1.4224)
			(stroke
				(width 0.1524)
				(type default)
			)
			(layer "F.SilkS")
		)
		(fp_line
			(start -2.1844 -0.0508)
			(end -2.7178 0.508)
			(stroke
				(width 0.1524)
				(type default)
			)
			(layer "F.SilkS")
		)
		(fp_line
			(start -2.7178 -0.508)
			(end -2.1844 -0.0508)
			(stroke
				(width 0.1524)
				(type default)
			)
			(layer "F.SilkS")
		)
		(fp_line
			(start -2.7432 -1.4224)
			(end -2.7432 1.4224)
			(stroke
				(width 0.1524)
				(type default)
			)
			(layer "F.SilkS")
		)
		(fp_line
			(start 2.1336 -1.4224)
			(end -2.7432 -1.4224)
			(stroke
				(width 0.1524)
				(type default)
			)
			(layer "F.SilkS")
		)
		(fp_poly
			(pts
				(xy -2.2098 -1.4224) (xy -2.2098 1.4224) (xy 2.2098 1.4224) (xy 2.2098 -1.4224)
			)
			(stroke
				(width 0)
				(type default)
			)
			(fill yes)
			(layer "F.SilkS")
		)
		(fp_rect
			(start -2.450084 2.999994)
			(end 2.450084 -2.999994)
			(stroke
				(width 0)
				(type default)
			)
			(fill no)
			(layer "F.CrtYd")
		)
		(fp_poly
			(pts
				(xy -2.8194 3.6322) (xy -2.8194 -3.6322) (xy 2.8194 -3.6322) (xy 2.8194 1.18364) (xy 2.450084 1.18364)
				(xy 2.450084 -2.999994) (xy -2.450084 -2.999994) (xy -2.450084 2.999994) (xy 2.450084 2.999994)
				(xy 2.450084 1.18618) (xy 2.8194 1.18618) (xy 2.8194 3.6322)
			)
			(stroke
				(width 0)
				(type default)
			)
			(fill no)
			(layer "F.CrtYd")
		)
		(fp_rect
			(start -2.8194 3.6322)
			(end 2.8194 -3.6322)
			(stroke
				(width 0)
				(type default)
			)
			(fill no)
			(layer "F.Fab")
		)
		(pad "1" smd rect
			(at -1.905 2.54 270)
			(size 0.635 1.651)
			(layers "F.Cu" "F.Mask" "F.Paste")
			(net "P5V_HDD6")
		)
		(pad "2" smd rect
			(at -0.635 2.54 270)
			(size 0.635 1.651)
			(layers "F.Cu" "F.Mask" "F.Paste")
			(net "P5V_HDD6")
		)
		(pad "3" smd rect
			(at 0.635 2.54 270)
			(size 0.635 1.651)
			(layers "F.Cu" "F.Mask" "F.Paste")
			(net "P5V_HDD6")
		)
		(pad "4" smd rect
			(at 1.905 2.54 270)
			(size 0.635 1.651)
			(layers "F.Cu" "F.Mask" "F.Paste")
			(net "SW_HDD6_P")
		)
		(pad "5" smd rect
			(at 1.905 -2.54 270)
			(size 0.635 1.651)
			(layers "F.Cu" "F.Mask" "F.Paste")
			(net "P5VB")
		)
		(pad "6" smd rect
			(at 0.635 -2.54 270)
			(size 0.635 1.651)
			(layers "F.Cu" "F.Mask" "F.Paste")
			(net "P5VB")
		)
		(pad "7" smd rect
			(at -0.635 -2.54 270)
			(size 0.635 1.651)
			(layers "F.Cu" "F.Mask" "F.Paste")
			(net "P5VB")
		)
		(pad "8" smd rect
			(at -1.905 -2.54 270)
			(size 0.635 1.651)
			(layers "F.Cu" "F.Mask" "F.Paste")
			(net "P5VB")
		)
	)
	(footprint ""
		(layer "F.Cu")
		(at 163.588446 -455.837036 180)
		(property "Reference" "R483"
			(at 0 0 180)
			(layer "F.SilkS")
			(hide yes)
			(effects
				(font
					(size 1.27 1.27)
				)
			)
		)
		(property "Value" "10KR2F-2-GP"
			(at 0.064008 -3.993896 180)
			(unlocked yes)
			(layer "F.Fab")
			(hide yes)
			(effects
				(font
					(size 1.016 1.016)
					(thickness 0.1524)
				)
			)
		)
		(property "Device Type" "R402H16"
			(at 0.064008 -5.517896 180)
			(unlocked yes)
			(layer "F.Fab")
			(hide yes)
			(effects
				(font
					(size 1.016 1.016)
					(thickness 0.1524)
				)
			)
		)
		(duplicate_pad_numbers_are_jumpers no)
		(fp_line
			(start 0.508 -0.9398)
			(end -0.508 -0.9398)
			(stroke
				(width 0.1524)
				(type default)
			)
			(layer "F.SilkS")
		)
		(fp_line
			(start -0.508 -0.9398)
			(end -0.508 0.9398)
			(stroke
				(width 0.1524)
				(type default)
			)
			(layer "F.SilkS")
		)
		(fp_rect
			(start -0.508 0.9398)
			(end 0.508 -0.9398)
			(stroke
				(width 0)
				(type default)
			)
			(fill no)
			(layer "F.CrtYd")
		)
		(fp_rect
			(start -0.508 0.9398)
			(end 0.508 -0.9398)
			(stroke
				(width 0)
				(type default)
			)
			(fill no)
			(layer "F.Fab")
		)
		(pad "1" smd custom
			(at 0 -0.4445 180)
			(size 0.1397 0.1397)
			(layers "F.Cu" "F.Mask" "F.Paste")
			(net "P5VB")
			(options
				(clearance outline)
				(anchor circle)
			)
			(primitives
				(gr_poly
					(pts
						(arc
							(start -0.1778 -0.2794)
							(mid -0.249642 -0.249642)
							(end -0.2794 -0.1778)
						)
						(arc
							(start -0.2794 0.1778)
							(mid -0.249642 0.249642)
							(end -0.1778 0.2794)
						)
						(arc
							(start 0.1778 0.2794)
							(mid 0.249642 0.249642)
							(end 0.2794 0.1778)
						)
						(arc
							(start 0.2794 -0.1778)
							(mid 0.249642 -0.249642)
							(end 0.1778 -0.2794)
						)
					)
					(width 0)
					(fill yes)
				)
			)
		)
		(pad "2" smd custom
			(at 0 0.4445 180)
			(size 0.1397 0.1397)
			(layers "F.Cu" "F.Mask" "F.Paste")
			(net "P5VB_DIV")
			(options
				(clearance outline)
				(anchor circle)
			)
			(primitives
				(gr_poly
					(pts
						(arc
							(start -0.1778 -0.2794)
							(mid -0.249642 -0.249642)
							(end -0.2794 -0.1778)
						)
						(arc
							(start -0.2794 0.1778)
							(mid -0.249642 0.249642)
							(end -0.1778 0.2794)
						)
						(arc
							(start 0.1778 0.2794)
							(mid 0.249642 0.249642)
							(end 0.2794 0.1778)
						)
						(arc
							(start 0.2794 -0.1778)
							(mid 0.249642 -0.249642)
							(end 0.1778 -0.2794)
						)
					)
					(width 0)
					(fill yes)
				)
			)
		)
	)
	(footprint ""
		(layer "F.Cu")
		(at 37.591746 -109.248702 180)
		(property "Reference" "U42"
			(at 0 0 180)
			(layer "F.SilkS")
			(hide yes)
			(effects
				(font
					(size 1.27 1.27)
				)
			)
		)
		(property "Value" "74LVC1G08GW-1-GP"
			(at -2.3368 -8.6868 180)
			(unlocked yes)
			(layer "F.Fab")
			(hide yes)
			(effects
				(font
					(size 1.016 1.016)
					(thickness 0.1524)
				)
			)
		)
		(property "Device Type" "SC70-5H44"
			(at -2.3114 -10.414 180)
			(unlocked yes)
			(layer "F.Fab")
			(hide yes)
			(effects
				(font
					(size 1.016 1.016)
					(thickness 0.1524)
				)
			)
		)
		(duplicate_pad_numbers_are_jumpers no)
		(fp_line
			(start 1.3843 -1.8034)
			(end 1.3843 -1.1176)
			(stroke
				(width 0.3302)
				(type default)
			)
			(layer "F.SilkS")
		)
		(fp_line
			(start 1.27 1.7018)
			(end -1.27 1.7018)
			(stroke
				(width 0.1524)
				(type default)
			)
			(layer "F.SilkS")
		)
		(fp_line
			(start 1.27 -1.7018)
			(end 1.27 1.7018)
			(stroke
				(width 0.1524)
				(type default)
			)
			(layer "F.SilkS")
		)
		(fp_line
			(start 0.6604 -1.8034)
			(end 1.3843 -1.8034)
			(stroke
				(width 0.3302)
				(type default)
			)
			(layer "F.SilkS")
		)
		(fp_line
			(start -1.27 1.7018)
			(end -1.27 -1.7018)
			(stroke
				(width 0.1524)
				(type default)
			)
			(layer "F.SilkS")
		)
		(fp_line
			(start -1.27 -1.7018)
			(end 1.27 -1.7018)
			(stroke
				(width 0.1524)
				(type default)
			)
			(layer "F.SilkS")
		)
		(fp_rect
			(start -1.524 1.9558)
			(end 1.524 -1.9558)
			(stroke
				(width 0)
				(type default)
			)
			(fill no)
			(layer "F.CrtYd")
		)
		(fp_poly
			(pts
				(xy -1.524 -1.9558) (xy 1.524 -1.9558) (xy 1.524 1.9558) (xy -1.524 1.9558)
			)
			(stroke
				(width 0)
				(type default)
			)
			(fill no)
			(layer "F.Fab")
		)
		(pad "1" smd rect
			(at 0.65024 -0.8255 180)
			(size 0.4064 1.2192)
			(layers "F.Cu" "F.Mask" "F.Paste")
			(net "SAS_EXP_B_PWR13")
		)
		(pad "2" smd rect
			(at 0 -0.8255 180)
			(size 0.4064 1.2192)
			(layers "F.Cu" "F.Mask" "F.Paste")
			(net "SAS_EXP_A_PWR13")
		)
		(pad "3" smd rect
			(at -0.65024 -0.8255 180)
			(size 0.4064 1.2192)
			(layers "F.Cu" "F.Mask" "F.Paste")
			(net "GND")
		)
		(pad "4" smd rect
			(at -0.65024 0.8255 180)
			(size 0.4064 1.2192)
			(layers "F.Cu" "F.Mask" "F.Paste")
			(net "DRIVE_PWR13")
		)
		(pad "5" smd rect
			(at 0.65024 0.8255 180)
			(size 0.4064 1.2192)
			(layers "F.Cu" "F.Mask" "F.Paste")
			(net "P3V3")
		)
	)
	(footprint ""
		(layer "F.Cu")
		(at 75.438 -394.1064 180)
		(property "Reference" "C203"
			(at 0 0 180)
			(layer "F.SilkS")
			(hide yes)
			(effects
				(font
					(size 1.27 1.27)
				)
			)
		)
		(property "Value" "SCD1U10V2KX-5GP"
			(at 1.1811 -2.7051 180)
			(unlocked yes)
			(layer "F.Fab")
			(hide yes)
			(effects
				(font
					(size 1.016 1.016)
					(thickness 0.1524)
				)
			)
		)
		(property "Device Type" "C402H22"
			(at 1.1811 -4.2291 180)
			(unlocked yes)
			(layer "F.Fab")
			(hide yes)
			(effects
				(font
					(size 1.016 1.016)
					(thickness 0.1524)
				)
			)
		)
		(duplicate_pad_numbers_are_jumpers no)
		(fp_rect
			(start -0.4318 0.9525)
			(end 0.4318 -0.9525)
			(stroke
				(width 0)
				(type default)
			)
			(fill no)
			(layer "F.CrtYd")
		)
		(fp_rect
			(start -0.4318 0.9525)
			(end 0.4318 -0.9525)
			(stroke
				(width 0)
				(type default)
			)
			(fill no)
			(layer "F.Fab")
		)
		(pad "1" smd custom
			(at 0 -0.4445 180)
			(size 0.1524 0.1524)
			(layers "F.Cu" "F.Mask" "F.Paste")
			(net "P3V3")
			(options
				(clearance outline)
				(anchor circle)
			)
			(primitives
				(gr_poly
					(pts
						(arc
							(start 0.3048 -0.2032)
							(mid 0.275042 -0.275042)
							(end 0.2032 -0.3048)
						)
						(arc
							(start -0.2032 -0.3048)
							(mid -0.275042 -0.275042)
							(end -0.3048 -0.2032)
						)
						(arc
							(start -0.3048 0.2032)
							(mid -0.275042 0.275042)
							(end -0.2032 0.3048)
						)
						(arc
							(start 0.2032 0.3048)
							(mid 0.275042 0.275042)
							(end 0.3048 0.2032)
						)
					)
					(width 0)
					(fill yes)
				)
			)
		)
		(pad "2" smd custom
			(at 0 0.4445 180)
			(size 0.1524 0.1524)
			(layers "F.Cu" "F.Mask" "F.Paste")
			(net "GND")
			(options
				(clearance outline)
				(anchor circle)
			)
			(primitives
				(gr_poly
					(pts
						(arc
							(start 0.3048 -0.2032)
							(mid 0.275042 -0.275042)
							(end 0.2032 -0.3048)
						)
						(arc
							(start -0.2032 -0.3048)
							(mid -0.275042 -0.275042)
							(end -0.3048 -0.2032)
						)
						(arc
							(start -0.3048 0.2032)
							(mid -0.275042 0.275042)
							(end -0.2032 0.3048)
						)
						(arc
							(start 0.2032 0.3048)
							(mid 0.275042 0.275042)
							(end 0.3048 0.2032)
						)
					)
					(width 0)
					(fill yes)
				)
			)
		)
	)
	(footprint ""
		(layer "F.Cu")
		(at 190.960756 -493.322102 -90)
		(property "Reference" "R113"
			(at 0 0 270)
			(layer "F.SilkS")
			(hide yes)
			(effects
				(font
					(size 1.27 1.27)
				)
			)
		)
		(property "Value" "0R2J-2-GP"
			(at 0.064008 -3.993896 270)
			(unlocked yes)
			(layer "F.Fab")
			(hide yes)
			(effects
				(font
					(size 1.016 1.016)
					(thickness 0.1524)
				)
			)
		)
		(property "Device Type" "R402H16"
			(at 0.064008 -5.517896 270)
			(unlocked yes)
			(layer "F.Fab")
			(hide yes)
			(effects
				(font
					(size 1.016 1.016)
					(thickness 0.1524)
				)
			)
		)
		(duplicate_pad_numbers_are_jumpers no)
		(fp_line
			(start -0.508 -0.9398)
			(end -0.508 0.9398)
			(stroke
				(width 0.1524)
				(type default)
			)
			(layer "F.SilkS")
		)
		(fp_line
			(start 0.508 -0.9398)
			(end -0.508 -0.9398)
			(stroke
				(width 0.1524)
				(type default)
			)
			(layer "F.SilkS")
		)
		(fp_rect
			(start -0.508 0.9398)
			(end 0.508 -0.9398)
			(stroke
				(width 0)
				(type default)
			)
			(fill no)
			(layer "F.CrtYd")
		)
		(fp_rect
			(start -0.508 0.9398)
			(end 0.508 -0.9398)
			(stroke
				(width 0)
				(type default)
			)
			(fill no)
			(layer "F.Fab")
		)
		(pad "1" smd custom
			(at 0 -0.4445 270)
			(size 0.1397 0.1397)
			(layers "F.Cu" "F.Mask" "F.Paste")
			(net "DRIVE_PWR0")
			(options
				(clearance outline)
				(anchor circle)
			)
			(primitives
				(gr_poly
					(pts
						(arc
							(start -0.1778 -0.2794)
							(mid -0.249642 -0.249642)
							(end -0.2794 -0.1778)
						)
						(arc
							(start -0.2794 0.1778)
							(mid -0.249642 0.249642)
							(end -0.1778 0.2794)
						)
						(arc
							(start 0.1778 0.2794)
							(mid 0.249642 0.249642)
							(end 0.2794 0.1778)
						)
						(arc
							(start 0.2794 -0.1778)
							(mid 0.249642 -0.249642)
							(end 0.1778 -0.2794)
						)
					)
					(width 0)
					(fill yes)
				)
			)
		)
		(pad "2" smd custom
			(at 0 0.4445 270)
			(size 0.1397 0.1397)
			(layers "F.Cu" "F.Mask" "F.Paste")
			(net "SW_PWR_HDD0")
			(options
				(clearance outline)
				(anchor circle)
			)
			(primitives
				(gr_poly
					(pts
						(arc
							(start -0.1778 -0.2794)
							(mid -0.249642 -0.249642)
							(end -0.2794 -0.1778)
						)
						(arc
							(start -0.2794 0.1778)
							(mid -0.249642 0.249642)
							(end -0.1778 0.2794)
						)
						(arc
							(start 0.1778 0.2794)
							(mid 0.249642 0.249642)
							(end 0.2794 0.1778)
						)
						(arc
							(start 0.2794 -0.1778)
							(mid 0.249642 -0.249642)
							(end 0.1778 -0.2794)
						)
					)
					(width 0)
					(fill yes)
				)
			)
		)
	)
	(footprint ""
		(layer "F.Cu")
		(at 56.3372 -477.6216 -90)
		(property "Reference" "Q56"
			(at 0 0 270)
			(layer "F.SilkS")
			(hide yes)
			(effects
				(font
					(size 1.27 1.27)
				)
			)
		)
		(property "Value" "2N7002DW-7F-GP"
			(at -2.3622 -8.2042 270)
			(unlocked yes)
			(layer "F.Fab")
			(hide yes)
			(effects
				(font
					(size 1.016 1.016)
					(thickness 0.1524)
				)
			)
		)
		(property "Device Type" "SOT-363H44"
			(at -2.3622 -10.1092 270)
			(unlocked yes)
			(layer "F.Fab")
			(hide yes)
			(effects
				(font
					(size 1.016 1.016)
					(thickness 0.1524)
				)
			)
		)
		(duplicate_pad_numbers_are_jumpers no)
		(fp_line
			(start -1.4478 1.7018)
			(end 1.4478 1.7018)
			(stroke
				(width 0.1524)
				(type default)
			)
			(layer "F.SilkS")
		)
		(fp_line
			(start 1.4478 1.7018)
			(end 1.4478 -1.7018)
			(stroke
				(width 0.1524)
				(type default)
			)
			(layer "F.SilkS")
		)
		(fp_line
			(start -1.27 1.524)
			(end -1.27 0.6604)
			(stroke
				(width 0.4826)
				(type default)
			)
			(layer "F.SilkS")
		)
		(fp_line
			(start -1.4478 -1.7018)
			(end -1.4478 1.7018)
			(stroke
				(width 0.1524)
				(type default)
			)
			(layer "F.SilkS")
		)
		(fp_line
			(start 1.4478 -1.7018)
			(end -1.4478 -1.7018)
			(stroke
				(width 0.1524)
				(type default)
			)
			(layer "F.SilkS")
		)
		(fp_poly
			(pts
				(xy -1.524 -1.778) (xy 1.524 -1.778) (xy 1.524 1.778) (xy -1.524 1.778)
			)
			(stroke
				(width 0)
				(type default)
			)
			(fill no)
			(layer "F.CrtYd")
		)
		(fp_poly
			(pts
				(xy -1.524 -1.778) (xy 1.524 -1.778) (xy 1.524 1.778) (xy -1.524 1.778)
			)
			(stroke
				(width 0)
				(type default)
			)
			(fill no)
			(layer "F.Fab")
		)
		(pad "1" smd rect
			(at -0.65024 0.9398 270)
			(size 0.4064 1.016)
			(layers "F.Cu" "F.Mask" "F.Paste")
			(net "P3V3_HDD5_LED")
		)
		(pad "2" smd rect
			(at 0 0.9398 270)
			(size 0.4064 1.016)
			(layers "F.Cu" "F.Mask" "F.Paste")
			(net "HDD5_LED_G")
		)
		(pad "3" smd rect
			(at 0.65024 0.9398 270)
			(size 0.4064 1.016)
			(layers "F.Cu" "F.Mask" "F.Paste")
			(net "P5VB")
		)
		(pad "4" smd rect
			(at 0.65024 -0.9398 270)
			(size 0.4064 1.016)
			(layers "F.Cu" "F.Mask" "F.Paste")
			(net "P5VB_HDD5_LED")
		)
		(pad "5" smd rect
			(at 0 -0.9398 270)
			(size 0.4064 1.016)
			(layers "F.Cu" "F.Mask" "F.Paste")
			(net "HDD5_LED_G")
		)
		(pad "6" smd rect
			(at -0.65024 -0.9398 270)
			(size 0.4064 1.016)
			(layers "F.Cu" "F.Mask" "F.Paste")
			(net "P3V3")
		)
	)
	(footprint ""
		(layer "F.Cu")
		(at 177.558446 -457.615036 -90)
		(property "Reference" "R361"
			(at 0 0 270)
			(layer "F.SilkS")
			(hide yes)
			(effects
				(font
					(size 1.27 1.27)
				)
			)
		)
		(property "Value" "0R2J-2-GP"
			(at 0.064008 -3.993896 270)
			(unlocked yes)
			(layer "F.Fab")
			(hide yes)
			(effects
				(font
					(size 1.016 1.016)
					(thickness 0.1524)
				)
			)
		)
		(property "Device Type" "R402H16"
			(at 0.064008 -5.517896 270)
			(unlocked yes)
			(layer "F.Fab")
			(hide yes)
			(effects
				(font
					(size 1.016 1.016)
					(thickness 0.1524)
				)
			)
		)
		(duplicate_pad_numbers_are_jumpers no)
		(fp_line
			(start -0.508 -0.9398)
			(end -0.508 0.9398)
			(stroke
				(width 0.1524)
				(type default)
			)
			(layer "F.SilkS")
		)
		(fp_line
			(start 0.508 -0.9398)
			(end -0.508 -0.9398)
			(stroke
				(width 0.1524)
				(type default)
			)
			(layer "F.SilkS")
		)
		(fp_rect
			(start -0.508 0.9398)
			(end 0.508 -0.9398)
			(stroke
				(width 0)
				(type default)
			)
			(fill no)
			(layer "F.CrtYd")
		)
		(fp_rect
			(start -0.508 0.9398)
			(end 0.508 -0.9398)
			(stroke
				(width 0)
				(type default)
			)
			(fill no)
			(layer "F.Fab")
		)
		(pad "1" smd custom
			(at 0 -0.4445 270)
			(size 0.1397 0.1397)
			(layers "F.Cu" "F.Mask" "F.Paste")
			(net "P5VC_DIV")
			(options
				(clearance outline)
				(anchor circle)
			)
			(primitives
				(gr_poly
					(pts
						(arc
							(start -0.1778 -0.2794)
							(mid -0.249642 -0.249642)
							(end -0.2794 -0.1778)
						)
						(arc
							(start -0.2794 0.1778)
							(mid -0.249642 0.249642)
							(end -0.1778 0.2794)
						)
						(arc
							(start 0.1778 0.2794)
							(mid 0.249642 0.249642)
							(end 0.2794 0.1778)
						)
						(arc
							(start 0.2794 -0.1778)
							(mid 0.249642 -0.249642)
							(end 0.1778 -0.2794)
						)
					)
					(width 0)
					(fill yes)
				)
			)
		)
		(pad "2" smd custom
			(at 0 0.4445 270)
			(size 0.1397 0.1397)
			(layers "F.Cu" "F.Mask" "F.Paste")
			(net "P5VC_SENSE")
			(options
				(clearance outline)
				(anchor circle)
			)
			(primitives
				(gr_poly
					(pts
						(arc
							(start -0.1778 -0.2794)
							(mid -0.249642 -0.249642)
							(end -0.2794 -0.1778)
						)
						(arc
							(start -0.2794 0.1778)
							(mid -0.249642 0.249642)
							(end -0.1778 0.2794)
						)
						(arc
							(start 0.1778 0.2794)
							(mid 0.249642 0.249642)
							(end 0.2794 0.1778)
						)
						(arc
							(start 0.2794 -0.1778)
							(mid 0.249642 -0.249642)
							(end 0.1778 -0.2794)
						)
					)
					(width 0)
					(fill yes)
				)
			)
		)
	)
)
